#ISCELL
  mstr_misc dns *
  *
#ISCELL
  pure_quanta quanta_title_block_c *
  *
#CELL
  pure_quanta tca9548apwr *
  page378_i1
#ISCELL
  standard offpage *
  page378_i10
#CELL
  pure_quanta q_res *
  page378_i100
#ISCELL
  standard offpage *
  page378_i101
#ISCELL
  standard offpage *
  page378_i102
#ISCELL
  standard offpage *
  page378_i103
#CELL
  pure_quanta q_res *
  page378_i104
#ISCELL
  standard offpage *
  page378_i105
#ISCELL
  standard offpage *
  page378_i106
#CELL
  pure_quanta q_res *
  page378_i107
#ISCELL
  pure_quanta_power universal_gnd *
  page378_i108
#CELL
  pure_quanta q_res *
  page378_i11
#ISCELL
  standard offpage *
  page378_i111
#ISCELL
  standard offpage *
  page378_i112
#ISCELL
  pure_quanta_power p1v0_aux *
  page378_i113
#ISCELL
  pure_quanta_power universal_gnd *
  page378_i115
#CELL
  pure_quanta conn3_210hp1030br1 *
  page378_i116
#CELL
  pure_quanta q_res *
  page378_i117
#CELL
  pure_quanta q_res *
  page378_i118
#CELL
  pure_quanta q_res *
  page378_i119
#ISCELL
  standard offpage *
  page378_i12
#CELL
  pure_quanta q_res *
  page378_i120
#CELL
  pure_quanta q_res *
  page378_i13
#CELL
  pure_quanta q_res *
  page378_i14
#ISCELL
  standard offpage *
  page378_i15
#ISCELL
  standard offpage *
  page378_i16
#CELL
  pure_quanta q_res *
  page378_i17
#CELL
  pure_quanta q_res *
  page378_i18
#ISCELL
  standard offpage *
  page378_i19
#ISCELL
  standard offpage *
  page378_i20
#CELL
  pure_quanta q_res *
  page378_i21
#CELL
  pure_quanta q_res *
  page378_i22
#ISCELL
  standard offpage *
  page378_i23
#ISCELL
  standard offpage *
  page378_i24
#CELL
  pure_quanta q_res *
  page378_i25
#CELL
  pure_quanta q_res *
  page378_i26
#ISCELL
  standard offpage *
  page378_i27
#ISCELL
  standard offpage *
  page378_i28
#ISCELL
  standard offpage *
  page378_i29
#ISCELL
  standard offpage *
  page378_i30
#CELL
  pure_quanta q_res *
  page378_i31
#CELL
  pure_quanta q_res *
  page378_i32
#ISCELL
  standard offpage *
  page378_i33
#ISCELL
  standard offpage *
  page378_i34
#CELL
  pure_quanta q_res *
  page378_i35
#CELL
  pure_quanta q_res *
  page378_i36
#ISCELL
  standard offpage *
  page378_i4
#ISCELL
  standard offpage *
  page378_i5
#CELL
  pure_quanta q_res *
  page378_i53
#CELL
  pure_quanta q_res *
  page378_i54
#CELL
  pure_quanta q_res *
  page378_i55
#CELL
  pure_quanta q_res *
  page378_i56
#CELL
  pure_quanta q_res *
  page378_i57
#CELL
  pure_quanta q_res *
  page378_i58
#CELL
  pure_quanta q_res *
  page378_i59
#CELL
  pure_quanta q_res *
  page378_i6
#CELL
  pure_quanta q_res *
  page378_i60
#ISCELL
  standard offpage *
  page378_i61
#ISCELL
  standard offpage *
  page378_i62
#ISCELL
  standard offpage *
  page378_i63
#ISCELL
  standard offpage *
  page378_i64
#ISCELL
  standard offpage *
  page378_i65
#ISCELL
  standard offpage *
  page378_i66
#ISCELL
  standard offpage *
  page378_i67
#ISCELL
  standard offpage *
  page378_i68
#ISCELL
  standard offpage *
  page378_i69
#CELL
  pure_quanta q_res *
  page378_i7
#ISCELL
  standard offpage *
  page378_i70
#ISCELL
  standard offpage *
  page378_i71
#ISCELL
  standard offpage *
  page378_i72
#ISCELL
  standard offpage *
  page378_i73
#ISCELL
  standard offpage *
  page378_i74
#ISCELL
  standard offpage *
  page378_i75
#ISCELL
  standard offpage *
  page378_i76
#CELL
  pure_quanta q_res *
  page378_i77
#CELL
  pure_quanta q_res *
  page378_i78
#CELL
  pure_quanta q_res *
  page378_i79
#ISCELL
  pure_quanta_power p1v0 *
  page378_i8
#CELL
  pure_quanta q_res *
  page378_i80
#ISCELL
  pure_quanta_power p1v0 *
  page378_i81
#CELL
  pure_quanta q_res *
  page378_i82
#CELL
  pure_quanta q_res *
  page378_i83
#CELL
  pure_quanta q_res *
  page378_i84
#CELL
  pure_quanta q_res *
  page378_i85
#ISCELL
  pure_quanta_power universal_gnd *
  page378_i86
#ISCELL
  pure_quanta_power p1v0_aux *
  page378_i87
#CELL
  pure_quanta q_cap *
  page378_i88
#ISCELL
  pure_quanta_power universal_gnd *
  page378_i89
#CELL
  pure_quanta q_res *
  page378_i9
#ISCELL
  standard offpage *
  page378_i90
#ISCELL
  standard offpage *
  page378_i91
#ISCELL
  standard offpage *
  page378_i92
#ISCELL
  pure_quanta_power universal_gnd *
  page378_i93
#CELL
  pure_quanta q_res *
  page378_i94
#CELL
  pure_quanta q_res *
  page378_i95
#CELL
  pure_quanta q_res *
  page378_i96
#CELL
  pure_quanta q_res *
  page378_i97
#CELL
  pure_quanta q_res *
  page378_i98
